FILE_TYPE = CONNECTIVITY;
{Allegro Design Entry HDL 17.4-2019 S026 (4007227) 1/17/2022}
"PAGE_NUMBER" = 46;
0"NC";
1"M_J_CPU1_SA_DQ<31:0>";
2"M_J_CPU1_SB_DQ<31:0>";
3"M_J_CPU1_SA_CB<7:0>";
4"M_J_CPU1_SB_CB<7:0>";
5"M_J_CPU1_SA_DQS_DP<9:0>";
6"M_J_CPU1_SA_DQS_DN<9:0>";
7"M_J_CPU1_SB_DQS_DP<9:0>";
8"M_J_CPU1_SB_DQS_DN<9:0>";
9"M_J_CPU1_SB_CA<6:0>";
10"M_J_CPU1_SA_CA<6:0>";
11"M_J_CPU1_ALERT_N";
12"M_J_CPU1_ALERT_R_N";
13"TP_M_J_CPU1_SA_TEST39J";
14"M_J_CPU1_CLK_DP<0>";
15"M_J_CPU1_CLK_DN<0>";
16"M_J_CPU1_SA_CS_N<0>";
17"M_J_CPU1_SA_CS_N<1>";
18"M_J_CPU1_SA_RSP<0>";
19"M_J_CPU1_SB_CS_N<0>";
20"M_J_CPU1_SB_CS_N<1>";
21"M_J_CPU1_SA_PAR";
22"M_J_CPU1_SB_PAR";
23"M_J_CPU1_SB_RSP<0>";
24"M_J_CPU1_RESET_N";
25"M_J_CPU1_SB_CA<6>";
26"M_J_CPU1_SA_CA<5>";
27"M_J_CPU1_SA_CA<6>";
28"M_J_CPU1_SA_CA<0>";
29"M_J_CPU1_SA_CA<1>";
30"M_J_CPU1_SA_CA<2>";
31"M_J_CPU1_SA_CA<3>";
32"M_J_CPU1_SA_CA<4>";
33"M_J_CPU1_SB_CA<0>";
34"M_J_CPU1_SB_CA<1>";
35"M_J_CPU1_SB_CA<2>";
36"M_J_CPU1_SB_CA<3>";
37"M_J_CPU1_SB_CA<4>";
38"M_J_CPU1_SB_CA<5>";
39"M_J_CPU1_SB_DQS_DN<8>";
40"M_J_CPU1_SB_DQS_DN<9>";
41"M_J_CPU1_SB_DQS_DP<8>";
42"M_J_CPU1_SB_DQS_DP<9>";
43"M_J_CPU1_SB_DQS_DN<4>";
44"M_J_CPU1_SB_DQS_DN<0>";
45"M_J_CPU1_SA_DQS_DN<8>";
46"M_J_CPU1_SA_DQS_DN<9>";
47"M_J_CPU1_SB_DQS_DN<1>";
48"M_J_CPU1_SB_DQS_DN<2>";
49"M_J_CPU1_SB_DQS_DN<3>";
50"M_J_CPU1_SB_DQS_DN<5>";
51"M_J_CPU1_SB_DQS_DN<6>";
52"M_J_CPU1_SB_DQS_DN<7>";
53"M_J_CPU1_SB_DQS_DP<5>";
54"M_J_CPU1_SB_DQS_DP<3>";
55"M_J_CPU1_SB_DQS_DP<4>";
56"M_J_CPU1_SB_DQS_DP<6>";
57"M_J_CPU1_SB_DQS_DP<7>";
58"M_J_CPU1_SA_DQS_DP<8>";
59"M_J_CPU1_SA_DQS_DP<9>";
60"M_J_CPU1_SB_DQS_DP<0>";
61"M_J_CPU1_SB_DQS_DP<1>";
62"M_J_CPU1_SB_DQS_DP<2>";
63"M_J_CPU1_SA_DQS_DN<4>";
64"M_J_CPU1_SA_DQS_DN<5>";
65"M_J_CPU1_SA_DQS_DN<7>";
66"M_J_CPU1_SA_DQS_DN<0>";
67"M_J_CPU1_SA_DQS_DN<1>";
68"M_J_CPU1_SA_DQS_DN<2>";
69"M_J_CPU1_SA_DQS_DN<3>";
70"M_J_CPU1_SA_DQS_DN<6>";
71"M_J_CPU1_SA_DQS_DP<4>";
72"M_J_CPU1_SA_DQS_DP<3>";
73"M_J_CPU1_SA_DQS_DP<5>";
74"M_J_CPU1_SA_DQS_DP<6>";
75"M_J_CPU1_SA_DQS_DP<7>";
76"M_J_CPU1_SA_DQS_DP<0>";
77"M_J_CPU1_SA_DQS_DP<1>";
78"M_J_CPU1_SA_DQS_DP<2>";
79"M_J_CPU1_SA_CB<6>";
80"M_J_CPU1_SA_CB<7>";
81"M_J_CPU1_SB_CB<0>";
82"M_J_CPU1_SB_CB<1>";
83"M_J_CPU1_SB_CB<2>";
84"M_J_CPU1_SB_CB<3>";
85"M_J_CPU1_SB_CB<4>";
86"M_J_CPU1_SB_CB<5>";
87"M_J_CPU1_SB_CB<6>";
88"M_J_CPU1_SB_CB<7>";
89"M_J_CPU1_SA_CB<0>";
90"M_J_CPU1_SA_CB<1>";
91"M_J_CPU1_SA_CB<2>";
92"M_J_CPU1_SA_CB<3>";
93"M_J_CPU1_SA_CB<4>";
94"M_J_CPU1_SA_CB<5>";
95"M_J_CPU1_SB_DQ<19>";
96"M_J_CPU1_SB_DQ<20>";
97"M_J_CPU1_SB_DQ<21>";
98"M_J_CPU1_SB_DQ<22>";
99"M_J_CPU1_SB_DQ<23>";
100"M_J_CPU1_SB_DQ<24>";
101"M_J_CPU1_SB_DQ<25>";
102"M_J_CPU1_SB_DQ<26>";
103"M_J_CPU1_SB_DQ<27>";
104"M_J_CPU1_SB_DQ<28>";
105"M_J_CPU1_SB_DQ<29>";
106"M_J_CPU1_SB_DQ<30>";
107"M_J_CPU1_SB_DQ<31>";
108"M_J_CPU1_SB_DQ<7>";
109"M_J_CPU1_SB_DQ<6>";
110"M_J_CPU1_SB_DQ<5>";
111"M_J_CPU1_SB_DQ<3>";
112"M_J_CPU1_SB_DQ<4>";
113"M_J_CPU1_SB_DQ<1>";
114"M_J_CPU1_SB_DQ<2>";
115"M_J_CPU1_SB_DQ<8>";
116"M_J_CPU1_SB_DQ<9>";
117"M_J_CPU1_SB_DQ<10>";
118"M_J_CPU1_SB_DQ<11>";
119"M_J_CPU1_SB_DQ<12>";
120"M_J_CPU1_SB_DQ<13>";
121"M_J_CPU1_SB_DQ<14>";
122"M_J_CPU1_SB_DQ<15>";
123"M_J_CPU1_SB_DQ<16>";
124"M_J_CPU1_SB_DQ<17>";
125"M_J_CPU1_SB_DQ<18>";
126"M_J_CPU1_SA_DQ<31>";
127"M_J_CPU1_SB_DQ<0>";
128"M_J_CPU1_SA_DQ<22>";
129"M_J_CPU1_SA_DQ<15>";
130"M_J_CPU1_SA_DQ<16>";
131"M_J_CPU1_SA_DQ<17>";
132"M_J_CPU1_SA_DQ<18>";
133"M_J_CPU1_SA_DQ<19>";
134"M_J_CPU1_SA_DQ<20>";
135"M_J_CPU1_SA_DQ<21>";
136"M_J_CPU1_SA_DQ<23>";
137"M_J_CPU1_SA_DQ<24>";
138"M_J_CPU1_SA_DQ<25>";
139"M_J_CPU1_SA_DQ<26>";
140"M_J_CPU1_SA_DQ<27>";
141"M_J_CPU1_SA_DQ<28>";
142"M_J_CPU1_SA_DQ<29>";
143"M_J_CPU1_SA_DQ<30>";
144"M_J_CPU1_SA_DQ<0>";
145"M_J_CPU1_SA_DQ<1>";
146"M_J_CPU1_SA_DQ<2>";
147"M_J_CPU1_SA_DQ<3>";
148"M_J_CPU1_SA_DQ<4>";
149"M_J_CPU1_SA_DQ<5>";
150"M_J_CPU1_SA_DQ<6>";
151"M_J_CPU1_SA_DQ<7>";
152"M_J_CPU1_SA_DQ<8>";
153"M_J_CPU1_SA_DQ<9>";
154"M_J_CPU1_SA_DQ<10>";
155"M_J_CPU1_SA_DQ<11>";
156"M_J_CPU1_SA_DQ<12>";
157"M_J_CPU1_SA_DQ<13>";
158"M_J_CPU1_SA_DQ<14>";
%"GENOA_SP5"
"10","(-4525,3525)","0","pure_quanta","I159";
;
LOCATION"U26"
$SEC"10"
CDS_SEC"10"
PART_TYPE"SMLF"
MATERIAL"IO"
VALUE"SOCKET6096_13568-001"
CDS_LIB"pure_quanta"
CDS_LMAN_SYM_OUTLINE"-650,2525,650,-2525"
NEEDS_NO_SIZE"TRUE"
PART_NUMBER"DGA^6000030";
"TEST39J"
$PN"BF18"13;
"MJB_DATA7"
$PN"CH18"108;
"MJB_DATA6"
$PN"CG16"109;
"MJB_DATA5"
$PN"CG17"110;
"MJB_DQS_H5"
$PN"CF18"53;
"MJB_DQS_L4"
$PN"BW17"43;
"MJB_DQS_L0"
$PN"CE16"44;
"MJA_DATA31"
$PN"AJ17"126;
"MJB_DATA0"
$PN"CB16"127;
"MJB_DATA3"
$PN"CD18"111;
"MJB_DATA4"
$PN"CF16"112;
"MJA_DQS_H4"
$PN"AL16"71;
"MJA_DQS_H8"
$PN"AG17"58;
"MJA_DQS_L4"
$PN"AM16"63;
"MJA_DQS_L5"
$PN"H18"64;
"MJA_DQS_L7"
$PN"Y18"65;
"MJA_DATA22"
$PN"AB16"128;
"MJA_CA5"
$PN"BB16"26;
"MJA_CA6"
$PN"BB18"27;
"MJ0_CLK_H"
$PN"BC16"14;
"MJ0_CLK_L"
$PN"BD16"15;
"MJ1_CLK_H"
$PN"BF16"0;
"MJ1_CLK_L"
$PN"BG16"0;
"MJA0_CS_L0"
$PN"AU16"16;
"MJA0_CS_L1"
$PN"AV18"17;
"MJA0_RSP_L"
$PN"BN17"18;
"MJA1_CS_L0"
$PN"AV16"0;
"MJA1_CS_L1"
$PN"AW17"0;
"MJA1_RSP_L"
$PN"BP18"0;
"MJA_CA0"
$PN"AW16"28;
"MJA_CA1"
$PN"AY16"29;
"MJA_CA2"
$PN"AY18"30;
"MJA_CA3"
$PN"BA17"31;
"MJA_CA4"
$PN"BA16"32;
"MJA_CHECK0"
$PN"AJ16"89;
"MJA_CHECK1"
$PN"AK18"90;
"MJA_CHECK2"
$PN"AK16"91;
"MJA_CHECK3"
$PN"AL17"92;
"MJA_CHECK4"
$PN"AN16"93;
"MJA_CHECK5"
$PN"AP18"94;
"MJA_CHECK6"
$PN"AP16"79;
"MJA_CHECK7"
$PN"AR17"80;
"MJA_DATA0"
$PN"E16"144;
"MJA_DATA1"
$PN"F18"145;
"MJA_DATA2"
$PN"F16"146;
"MJA_DATA3"
$PN"G17"147;
"MJA_DATA4"
$PN"J16"148;
"MJA_DATA5"
$PN"K18"149;
"MJA_DATA6"
$PN"K16"150;
"MJA_DATA7"
$PN"L17"151;
"MJA_DATA8"
$PN"L16"152;
"MJA_DATA9"
$PN"M18"153;
"MJA_DATA10"
$PN"M16"154;
"MJA_DATA11"
$PN"N17"155;
"MJA_DATA12"
$PN"R16"156;
"MJA_DATA13"
$PN"T18"157;
"MJA_DATA14"
$PN"T16"158;
"MJA_DATA15"
$PN"U17"129;
"MJA_DATA16"
$PN"U16"130;
"MJA_DATA17"
$PN"V18"131;
"MJA_DATA18"
$PN"V16"132;
"MJA_DATA19"
$PN"W17"133;
"MJA_DATA20"
$PN"AA16"134;
"MJA_DATA21"
$PN"AB18"135;
"MJA_DATA23"
$PN"AC17"136;
"MJA_DATA24"
$PN"AC16"137;
"MJA_DATA25"
$PN"AD18"138;
"MJA_DATA26"
$PN"AD16"139;
"MJA_DATA27"
$PN"AE17"140;
"MJA_DATA28"
$PN"AG16"141;
"MJA_DATA29"
$PN"AH18"142;
"MJA_DATA30"
$PN"AH16"143;
"MJA_DQS_H0"
$PN"G16"76;
"MJA_DQS_H1"
$PN"N16"77;
"MJA_DQS_H2"
$PN"W16"78;
"MJA_DQS_H3"
$PN"AE16"72;
"MJA_DQS_H5"
$PN"J17"73;
"MJA_DQS_H6"
$PN"R17"74;
"MJA_DQS_H7"
$PN"AA17"75;
"MJA_DQS_H9"
$PN"AN17"59;
"MJA_DQS_L0"
$PN"H16"66;
"MJA_DQS_L1"
$PN"P16"67;
"MJA_DQS_L2"
$PN"Y16"68;
"MJA_DQS_L3"
$PN"AF16"69;
"MJA_DQS_L6"
$PN"P18"70;
"MJA_DQS_L8"
$PN"AF18"45;
"MJA_DQS_L9"
$PN"AM18"46;
"MJA_PAR"
$PN"BC17"21;
"MJB0_CS_L0"
$PN"BM18"19;
"MJB0_CS_L1"
$PN"BN16"20;
"MJB0_RSP_L"
$PN"BP16"23;
"MJB1_CS_L0"
$PN"BL16"0;
"MJB1_CS_L1"
$PN"BM16"0;
"MJB1_RSP_L"
$PN"BR16"0;
"MJB_CA0"
$PN"BG17"33;
"MJB_CA1"
$PN"BH18"34;
"MJB_CA2"
$PN"BH16"35;
"MJB_CA3"
$PN"BJ16"36;
"MJB_CA4"
$PN"BJ17"37;
"MJB_CA5"
$PN"BK18"38;
"MJB_CA6"
$PN"BK16"25;
"MJB_CHECK0"
$PN"BY16"81;
"MJB_CHECK1"
$PN"CA17"82;
"MJB_CHECK2"
$PN"CA16"83;
"MJB_CHECK3"
$PN"CB18"84;
"MJB_CHECK4"
$PN"BT16"85;
"MJB_CHECK5"
$PN"BU17"86;
"MJB_CHECK6"
$PN"BU16"87;
"MJB_CHECK7"
$PN"BV18"88;
"MJB_DATA1"
$PN"CC17"113;
"MJB_DATA2"
$PN"CC16"114;
"MJB_DATA8"
$PN"CH16"115;
"MJB_DATA9"
$PN"CJ17"116;
"MJB_DATA10"
$PN"CJ16"117;
"MJB_DATA11"
$PN"CK18"118;
"MJB_DATA12"
$PN"CM16"119;
"MJB_DATA13"
$PN"CN17"120;
"MJB_DATA14"
$PN"CN16"121;
"MJB_DATA15"
$PN"CP18"122;
"MJB_DATA16"
$PN"CP16"123;
"MJB_DATA17"
$PN"CR17"124;
"MJB_DATA18"
$PN"CR16"125;
"MJB_DATA19"
$PN"CT18"95;
"MJB_DATA20"
$PN"CV16"96;
"MJB_DATA21"
$PN"CW17"97;
"MJB_DATA22"
$PN"CW16"98;
"MJB_DATA23"
$PN"CY18"99;
"MJB_DATA24"
$PN"CY16"100;
"MJB_DATA25"
$PN"DA17"101;
"MJB_DATA26"
$PN"DA16"102;
"MJB_DATA27"
$PN"DB18"103;
"MJB_DATA28"
$PN"DD16"104;
"MJB_DATA29"
$PN"DE17"105;
"MJB_DATA30"
$PN"DE16"106;
"MJB_DATA31"
$PN"DF16"107;
"MJB_DQS_H0"
$PN"CD16"60;
"MJB_DQS_H1"
$PN"CK16"61;
"MJB_DQS_H2"
$PN"CT16"62;
"MJB_DQS_H3"
$PN"DB16"54;
"MJB_DQS_H4"
$PN"BY18"55;
"MJB_DQS_H6"
$PN"CM18"56;
"MJB_DQS_H7"
$PN"CV18"57;
"MJB_DQS_H8"
$PN"DD18"41;
"MJB_DQS_H9"
$PN"BV16"42;
"MJB_DQS_L1"
$PN"CL16"47;
"MJB_DQS_L2"
$PN"CU16"48;
"MJB_DQS_L3"
$PN"DC16"49;
"MJB_DQS_L5"
$PN"CE17"50;
"MJB_DQS_L6"
$PN"CL17"51;
"MJB_DQS_L7"
$PN"CU17"52;
"MJB_DQS_L8"
$PN"DC17"39;
"MJB_DQS_L9"
$PN"BW16"40;
"MJB_PAR"
$PN"BL17"22;
"MJ_ALERT_L"
$PN"AT18"12;
"MJ_RESET_L"
$PN"AU17"24;
%"TAP"
"1","(-3250,5900)","0","mstr_standard","I161";
;
CDS_LIB"mstr_standard"
BODY_TYPE"PLUMBING"
HDL_TAP"TRUE";
"B \NAC \NWC"1;
"S \NAC"
BN"0"144;
%"TAP"
"1","(-3250,5850)","0","mstr_standard","I162";
;
CDS_LIB"mstr_standard"
BODY_TYPE"PLUMBING"
HDL_TAP"TRUE";
"B \NAC \NWC"1;
"S \NAC"
BN"1"145;
%"TAP"
"1","(-3250,5800)","0","mstr_standard","I163";
;
CDS_LIB"mstr_standard"
BODY_TYPE"PLUMBING"
HDL_TAP"TRUE";
"B \NAC \NWC"1;
"S \NAC"
BN"2"146;
%"TAP"
"1","(-3250,5700)","0","mstr_standard","I164";
;
CDS_LIB"mstr_standard"
BODY_TYPE"PLUMBING"
HDL_TAP"TRUE";
"B \NAC \NWC"1;
"S \NAC"
BN"4"148;
%"TAP"
"1","(-3250,5750)","0","mstr_standard","I165";
;
CDS_LIB"mstr_standard"
BODY_TYPE"PLUMBING"
HDL_TAP"TRUE";
"B \NAC \NWC"1;
"S \NAC"
BN"3"147;
%"TAP"
"1","(-3250,5650)","0","mstr_standard","I166";
;
CDS_LIB"mstr_standard"
BODY_TYPE"PLUMBING"
HDL_TAP"TRUE";
"B \NAC \NWC"1;
"S \NAC"
BN"5"149;
%"TAP"
"1","(-3250,5600)","0","mstr_standard","I167";
;
CDS_LIB"mstr_standard"
BODY_TYPE"PLUMBING"
HDL_TAP"TRUE";
"B \NAC \NWC"1;
"S \NAC"
BN"6"150;
%"TAP"
"1","(-3250,5550)","0","mstr_standard","I168";
;
CDS_LIB"mstr_standard"
BODY_TYPE"PLUMBING"
HDL_TAP"TRUE";
"B \NAC \NWC"1;
"S \NAC"
BN"7"151;
%"TAP"
"1","(-3250,5400)","0","mstr_standard","I169";
;
CDS_LIB"mstr_standard"
BODY_TYPE"PLUMBING"
HDL_TAP"TRUE";
"B \NAC \NWC"1;
"S \NAC"
BN"9"153;
%"TAP"
"1","(-3250,5450)","0","mstr_standard","I170";
;
CDS_LIB"mstr_standard"
BODY_TYPE"PLUMBING"
HDL_TAP"TRUE";
"B \NAC \NWC"1;
"S \NAC"
BN"8"152;
%"TAP"
"1","(-3250,5350)","0","mstr_standard","I171";
;
CDS_LIB"mstr_standard"
BODY_TYPE"PLUMBING"
HDL_TAP"TRUE";
"B \NAC \NWC"1;
"S \NAC"
BN"10"154;
%"TAP"
"1","(-3250,5300)","0","mstr_standard","I172";
;
CDS_LIB"mstr_standard"
BODY_TYPE"PLUMBING"
HDL_TAP"TRUE";
"B \NAC \NWC"1;
"S \NAC"
BN"11"155;
%"TAP"
"1","(-3250,5250)","0","mstr_standard","I173";
;
CDS_LIB"mstr_standard"
BODY_TYPE"PLUMBING"
HDL_TAP"TRUE";
"B \NAC \NWC"1;
"S \NAC"
BN"12"156;
%"TAP"
"1","(-3250,5200)","0","mstr_standard","I174";
;
CDS_LIB"mstr_standard"
BODY_TYPE"PLUMBING"
HDL_TAP"TRUE";
"B \NAC \NWC"1;
"S \NAC"
BN"13"157;
%"TAP"
"1","(-3250,5150)","0","mstr_standard","I175";
;
CDS_LIB"mstr_standard"
BODY_TYPE"PLUMBING"
HDL_TAP"TRUE";
"B \NAC \NWC"1;
"S \NAC"
BN"14"158;
%"TAP"
"1","(-3250,5100)","0","mstr_standard","I176";
;
CDS_LIB"mstr_standard"
BODY_TYPE"PLUMBING"
HDL_TAP"TRUE";
"B \NAC \NWC"1;
"S \NAC"
BN"15"129;
%"TAP"
"1","(-3250,5000)","0","mstr_standard","I177";
;
CDS_LIB"mstr_standard"
BODY_TYPE"PLUMBING"
HDL_TAP"TRUE";
"B \NAC \NWC"1;
"S \NAC"
BN"16"130;
%"TAP"
"1","(-3250,4950)","0","mstr_standard","I178";
;
CDS_LIB"mstr_standard"
BODY_TYPE"PLUMBING"
HDL_TAP"TRUE";
"B \NAC \NWC"1;
"S \NAC"
BN"17"131;
%"TAP"
"1","(-3250,4900)","0","mstr_standard","I179";
;
CDS_LIB"mstr_standard"
BODY_TYPE"PLUMBING"
HDL_TAP"TRUE";
"B \NAC \NWC"1;
"S \NAC"
BN"18"132;
%"TAP"
"1","(-3250,4850)","0","mstr_standard","I180";
;
CDS_LIB"mstr_standard"
BODY_TYPE"PLUMBING"
HDL_TAP"TRUE";
"B \NAC \NWC"1;
"S \NAC"
BN"19"133;
%"TAP"
"1","(-3250,4800)","0","mstr_standard","I181";
;
CDS_LIB"mstr_standard"
BODY_TYPE"PLUMBING"
HDL_TAP"TRUE";
"B \NAC \NWC"1;
"S \NAC"
BN"20"134;
%"TAP"
"1","(-3250,4750)","0","mstr_standard","I182";
;
CDS_LIB"mstr_standard"
BODY_TYPE"PLUMBING"
HDL_TAP"TRUE";
"B \NAC \NWC"1;
"S \NAC"
BN"21"135;
%"TAP"
"1","(-3250,4650)","0","mstr_standard","I183";
;
CDS_LIB"mstr_standard"
BODY_TYPE"PLUMBING"
HDL_TAP"TRUE";
"B \NAC \NWC"1;
"S \NAC"
BN"23"136;
%"TAP"
"1","(-3250,4700)","0","mstr_standard","I184";
;
CDS_LIB"mstr_standard"
BODY_TYPE"PLUMBING"
HDL_TAP"TRUE";
"B \NAC \NWC"1;
"S \NAC"
BN"22"128;
%"TAP"
"1","(-3250,4500)","0","mstr_standard","I185";
;
CDS_LIB"mstr_standard"
BODY_TYPE"PLUMBING"
HDL_TAP"TRUE";
"B \NAC \NWC"1;
"S \NAC"
BN"25"138;
%"TAP"
"1","(-3250,4550)","0","mstr_standard","I186";
;
CDS_LIB"mstr_standard"
BODY_TYPE"PLUMBING"
HDL_TAP"TRUE";
"B \NAC \NWC"1;
"S \NAC"
BN"24"137;
%"TAP"
"1","(-3250,4450)","0","mstr_standard","I187";
;
CDS_LIB"mstr_standard"
BODY_TYPE"PLUMBING"
HDL_TAP"TRUE";
"B \NAC \NWC"1;
"S \NAC"
BN"26"139;
%"TAP"
"1","(-3250,4400)","0","mstr_standard","I188";
;
CDS_LIB"mstr_standard"
BODY_TYPE"PLUMBING"
HDL_TAP"TRUE";
"B \NAC \NWC"1;
"S \NAC"
BN"27"140;
%"TAP"
"1","(-3250,4350)","0","mstr_standard","I189";
;
CDS_LIB"mstr_standard"
BODY_TYPE"PLUMBING"
HDL_TAP"TRUE";
"B \NAC \NWC"1;
"S \NAC"
BN"28"141;
%"TAP"
"1","(-3250,4300)","0","mstr_standard","I190";
;
CDS_LIB"mstr_standard"
BODY_TYPE"PLUMBING"
HDL_TAP"TRUE";
"B \NAC \NWC"1;
"S \NAC"
BN"29"142;
%"TAP"
"1","(-3250,4250)","0","mstr_standard","I191";
;
CDS_LIB"mstr_standard"
BODY_TYPE"PLUMBING"
HDL_TAP"TRUE";
"B \NAC \NWC"1;
"S \NAC"
BN"30"143;
%"TAP"
"1","(-3250,4100)","0","mstr_standard","I192";
;
CDS_LIB"mstr_standard"
BODY_TYPE"PLUMBING"
HDL_TAP"TRUE";
"B \NAC \NWC"2;
"S \NAC"
BN"0"127;
%"TAP"
"1","(-3250,4200)","0","mstr_standard","I193";
;
CDS_LIB"mstr_standard"
BODY_TYPE"PLUMBING"
HDL_TAP"TRUE";
"B \NAC \NWC"1;
"S \NAC"
BN"31"126;
%"TAP"
"1","(-3250,4000)","0","mstr_standard","I196";
;
CDS_LIB"mstr_standard"
BODY_TYPE"PLUMBING"
HDL_TAP"TRUE";
"B \NAC \NWC"2;
"S \NAC"
BN"2"114;
%"TAP"
"1","(-3250,4050)","0","mstr_standard","I197";
;
CDS_LIB"mstr_standard"
BODY_TYPE"PLUMBING"
HDL_TAP"TRUE";
"B \NAC \NWC"2;
"S \NAC"
BN"1"113;
%"TAP"
"1","(-3250,3900)","0","mstr_standard","I198";
;
CDS_LIB"mstr_standard"
BODY_TYPE"PLUMBING"
HDL_TAP"TRUE";
"B \NAC \NWC"2;
"S \NAC"
BN"4"112;
%"TAP"
"1","(-3250,3950)","0","mstr_standard","I199";
;
CDS_LIB"mstr_standard"
BODY_TYPE"PLUMBING"
HDL_TAP"TRUE";
"B \NAC \NWC"2;
"S \NAC"
BN"3"111;
%"TAP"
"1","(-3250,3850)","0","mstr_standard","I200";
;
CDS_LIB"mstr_standard"
BODY_TYPE"PLUMBING"
HDL_TAP"TRUE";
"B \NAC \NWC"2;
"S \NAC"
BN"5"110;
%"TAP"
"1","(-3250,3750)","0","mstr_standard","I201";
;
CDS_LIB"mstr_standard"
BODY_TYPE"PLUMBING"
HDL_TAP"TRUE";
"B \NAC \NWC"2;
"S \NAC"
BN"7"108;
%"TAP"
"1","(-3250,3800)","0","mstr_standard","I202";
;
CDS_LIB"mstr_standard"
BODY_TYPE"PLUMBING"
HDL_TAP"TRUE";
"B \NAC \NWC"2;
"S \NAC"
BN"6"109;
%"TAP"
"1","(-3250,3650)","0","mstr_standard","I203";
;
CDS_LIB"mstr_standard"
BODY_TYPE"PLUMBING"
HDL_TAP"TRUE";
"B \NAC \NWC"2;
"S \NAC"
BN"8"115;
%"TAP"
"1","(-3250,3600)","0","mstr_standard","I204";
;
CDS_LIB"mstr_standard"
BODY_TYPE"PLUMBING"
HDL_TAP"TRUE";
"B \NAC \NWC"2;
"S \NAC"
BN"9"116;
%"TAP"
"1","(-3250,3500)","0","mstr_standard","I205";
;
CDS_LIB"mstr_standard"
BODY_TYPE"PLUMBING"
HDL_TAP"TRUE";
"B \NAC \NWC"2;
"S \NAC"
BN"11"118;
%"TAP"
"1","(-3250,3550)","0","mstr_standard","I206";
;
CDS_LIB"mstr_standard"
BODY_TYPE"PLUMBING"
HDL_TAP"TRUE";
"B \NAC \NWC"2;
"S \NAC"
BN"10"117;
%"TAP"
"1","(-3250,3450)","0","mstr_standard","I207";
;
CDS_LIB"mstr_standard"
BODY_TYPE"PLUMBING"
HDL_TAP"TRUE";
"B \NAC \NWC"2;
"S \NAC"
BN"12"119;
%"TAP"
"1","(-3250,3400)","0","mstr_standard","I208";
;
CDS_LIB"mstr_standard"
BODY_TYPE"PLUMBING"
HDL_TAP"TRUE";
"B \NAC \NWC"2;
"S \NAC"
BN"13"120;
%"TAP"
"1","(-3250,3350)","0","mstr_standard","I209";
;
CDS_LIB"mstr_standard"
BODY_TYPE"PLUMBING"
HDL_TAP"TRUE";
"B \NAC \NWC"2;
"S \NAC"
BN"14"121;
%"TAP"
"1","(-3250,3300)","0","mstr_standard","I210";
;
CDS_LIB"mstr_standard"
BODY_TYPE"PLUMBING"
HDL_TAP"TRUE";
"B \NAC \NWC"2;
"S \NAC"
BN"15"122;
%"TAP"
"1","(-3250,3200)","0","mstr_standard","I211";
;
CDS_LIB"mstr_standard"
BODY_TYPE"PLUMBING"
HDL_TAP"TRUE";
"B \NAC \NWC"2;
"S \NAC"
BN"16"123;
%"TAP"
"1","(-3250,3150)","0","mstr_standard","I212";
;
CDS_LIB"mstr_standard"
BODY_TYPE"PLUMBING"
HDL_TAP"TRUE";
"B \NAC \NWC"2;
"S \NAC"
BN"17"124;
%"TAP"
"1","(-3250,3100)","0","mstr_standard","I213";
;
CDS_LIB"mstr_standard"
BODY_TYPE"PLUMBING"
HDL_TAP"TRUE";
"B \NAC \NWC"2;
"S \NAC"
BN"18"125;
%"TAP"
"1","(-3250,2950)","0","mstr_standard","I214";
;
CDS_LIB"mstr_standard"
BODY_TYPE"PLUMBING"
HDL_TAP"TRUE";
"B \NAC \NWC"2;
"S \NAC"
BN"21"97;
%"TAP"
"1","(-3250,3000)","0","mstr_standard","I215";
;
CDS_LIB"mstr_standard"
BODY_TYPE"PLUMBING"
HDL_TAP"TRUE";
"B \NAC \NWC"2;
"S \NAC"
BN"20"96;
%"TAP"
"1","(-3250,3050)","0","mstr_standard","I216";
;
CDS_LIB"mstr_standard"
BODY_TYPE"PLUMBING"
HDL_TAP"TRUE";
"B \NAC \NWC"2;
"S \NAC"
BN"19"95;
%"TAP"
"1","(-3250,2900)","0","mstr_standard","I217";
;
CDS_LIB"mstr_standard"
BODY_TYPE"PLUMBING"
HDL_TAP"TRUE";
"B \NAC \NWC"2;
"S \NAC"
BN"22"98;
%"TAP"
"1","(-3250,2850)","0","mstr_standard","I218";
;
CDS_LIB"mstr_standard"
BODY_TYPE"PLUMBING"
HDL_TAP"TRUE";
"B \NAC \NWC"2;
"S \NAC"
BN"23"99;
%"TAP"
"1","(-3250,2700)","0","mstr_standard","I219";
;
CDS_LIB"mstr_standard"
BODY_TYPE"PLUMBING"
HDL_TAP"TRUE";
"B \NAC \NWC"2;
"S \NAC"
BN"25"101;
%"TAP"
"1","(-3250,2750)","0","mstr_standard","I220";
;
CDS_LIB"mstr_standard"
BODY_TYPE"PLUMBING"
HDL_TAP"TRUE";
"B \NAC \NWC"2;
"S \NAC"
BN"24"100;
%"TAP"
"1","(-3250,2650)","0","mstr_standard","I221";
;
CDS_LIB"mstr_standard"
BODY_TYPE"PLUMBING"
HDL_TAP"TRUE";
"B \NAC \NWC"2;
"S \NAC"
BN"26"102;
%"TAP"
"1","(-3250,2600)","0","mstr_standard","I222";
;
CDS_LIB"mstr_standard"
BODY_TYPE"PLUMBING"
HDL_TAP"TRUE";
"B \NAC \NWC"2;
"S \NAC"
BN"27"103;
%"TAP"
"1","(-3250,2450)","0","mstr_standard","I223";
;
CDS_LIB"mstr_standard"
BODY_TYPE"PLUMBING"
HDL_TAP"TRUE";
"B \NAC \NWC"2;
"S \NAC"
BN"30"106;
%"TAP"
"1","(-3250,2550)","0","mstr_standard","I224";
;
CDS_LIB"mstr_standard"
BODY_TYPE"PLUMBING"
HDL_TAP"TRUE";
"B \NAC \NWC"2;
"S \NAC"
BN"28"104;
%"TAP"
"1","(-3250,2500)","0","mstr_standard","I225";
;
CDS_LIB"mstr_standard"
BODY_TYPE"PLUMBING"
HDL_TAP"TRUE";
"B \NAC \NWC"2;
"S \NAC"
BN"29"105;
%"TAP"
"1","(-3250,2400)","0","mstr_standard","I226";
;
CDS_LIB"mstr_standard"
BODY_TYPE"PLUMBING"
HDL_TAP"TRUE";
"B \NAC \NWC"2;
"S \NAC"
BN"31"107;
%"TAP"
"1","(-3250,2300)","0","mstr_standard","I227";
;
CDS_LIB"mstr_standard"
BODY_TYPE"PLUMBING"
HDL_TAP"TRUE";
"B \NAC \NWC"3;
"S \NAC"
BN"0"89;
%"TAP"
"1","(-3250,2250)","0","mstr_standard","I228";
;
CDS_LIB"mstr_standard"
BODY_TYPE"PLUMBING"
HDL_TAP"TRUE";
"B \NAC \NWC"3;
"S \NAC"
BN"1"90;
%"TAP"
"1","(-3250,2200)","0","mstr_standard","I229";
;
CDS_LIB"mstr_standard"
BODY_TYPE"PLUMBING"
HDL_TAP"TRUE";
"B \NAC \NWC"3;
"S \NAC"
BN"2"91;
%"TAP"
"1","(-3250,2150)","0","mstr_standard","I230";
;
CDS_LIB"mstr_standard"
BODY_TYPE"PLUMBING"
HDL_TAP"TRUE";
"B \NAC \NWC"3;
"S \NAC"
BN"3"92;
%"TAP"
"1","(-3250,2100)","0","mstr_standard","I231";
;
CDS_LIB"mstr_standard"
BODY_TYPE"PLUMBING"
HDL_TAP"TRUE";
"B \NAC \NWC"3;
"S \NAC"
BN"4"93;
%"TAP"
"1","(-3250,2050)","0","mstr_standard","I232";
;
CDS_LIB"mstr_standard"
BODY_TYPE"PLUMBING"
HDL_TAP"TRUE";
"B \NAC \NWC"3;
"S \NAC"
BN"5"94;
%"TAP"
"1","(-3250,1950)","0","mstr_standard","I234";
;
CDS_LIB"mstr_standard"
BODY_TYPE"PLUMBING"
HDL_TAP"TRUE";
"B \NAC \NWC"3;
"S \NAC"
BN"7"80;
%"TAP"
"1","(-3250,2000)","0","mstr_standard","I235";
;
CDS_LIB"mstr_standard"
BODY_TYPE"PLUMBING"
HDL_TAP"TRUE";
"B \NAC \NWC"3;
"S \NAC"
BN"6"79;
%"TAP"
"1","(-3250,1800)","0","mstr_standard","I236";
;
CDS_LIB"mstr_standard"
BODY_TYPE"PLUMBING"
HDL_TAP"TRUE";
"B \NAC \NWC"4;
"S \NAC"
BN"1"82;
%"TAP"
"1","(-3250,1850)","0","mstr_standard","I237";
;
CDS_LIB"mstr_standard"
BODY_TYPE"PLUMBING"
HDL_TAP"TRUE";
"B \NAC \NWC"4;
"S \NAC"
BN"0"81;
%"TAP"
"1","(-3250,1700)","0","mstr_standard","I238";
;
CDS_LIB"mstr_standard"
BODY_TYPE"PLUMBING"
HDL_TAP"TRUE";
"B \NAC \NWC"4;
"S \NAC"
BN"3"84;
%"TAP"
"1","(-3250,1750)","0","mstr_standard","I239";
;
CDS_LIB"mstr_standard"
BODY_TYPE"PLUMBING"
HDL_TAP"TRUE";
"B \NAC \NWC"4;
"S \NAC"
BN"2"83;
%"TAP"
"1","(-3250,1650)","0","mstr_standard","I240";
;
CDS_LIB"mstr_standard"
BODY_TYPE"PLUMBING"
HDL_TAP"TRUE";
"B \NAC \NWC"4;
"S \NAC"
BN"4"85;
%"TAP"
"1","(-3250,1600)","0","mstr_standard","I241";
;
CDS_LIB"mstr_standard"
BODY_TYPE"PLUMBING"
HDL_TAP"TRUE";
"B \NAC \NWC"4;
"S \NAC"
BN"5"86;
%"TAP"
"1","(-3250,1550)","0","mstr_standard","I242";
;
CDS_LIB"mstr_standard"
BODY_TYPE"PLUMBING"
HDL_TAP"TRUE";
"B \NAC \NWC"4;
"S \NAC"
BN"6"87;
%"TAP"
"1","(-3250,1500)","0","mstr_standard","I243";
;
CDS_LIB"mstr_standard"
BODY_TYPE"PLUMBING"
HDL_TAP"TRUE";
"B \NAC \NWC"4;
"S \NAC"
BN"7"88;
%"TAP"
"1","(-5675,5900)","2","mstr_standard","I244";
;
CDS_LIB"mstr_standard"
BODY_TYPE"PLUMBING"
HDL_TAP"TRUE";
"B \NAC \NWC"5;
"S \NAC"
BN"0"76;
%"TAP"
"1","(-5675,5800)","2","mstr_standard","I245";
;
CDS_LIB"mstr_standard"
BODY_TYPE"PLUMBING"
HDL_TAP"TRUE";
"B \NAC \NWC"5;
"S \NAC"
BN"1"77;
%"TAP"
"1","(-5675,5700)","2","mstr_standard","I246";
;
CDS_LIB"mstr_standard"
BODY_TYPE"PLUMBING"
HDL_TAP"TRUE";
"B \NAC \NWC"5;
"S \NAC"
BN"2"78;
%"TAP"
"1","(-5675,5600)","2","mstr_standard","I247";
;
CDS_LIB"mstr_standard"
BODY_TYPE"PLUMBING"
HDL_TAP"TRUE";
"B \NAC \NWC"5;
"S \NAC"
BN"3"72;
%"TAP"
"1","(-5675,5500)","2","mstr_standard","I248";
;
CDS_LIB"mstr_standard"
BODY_TYPE"PLUMBING"
HDL_TAP"TRUE";
"B \NAC \NWC"5;
"S \NAC"
BN"4"71;
%"TAP"
"1","(-5675,5400)","2","mstr_standard","I249";
;
CDS_LIB"mstr_standard"
BODY_TYPE"PLUMBING"
HDL_TAP"TRUE";
"B \NAC \NWC"5;
"S \NAC"
BN"5"73;
%"TAP"
"1","(-5675,5300)","2","mstr_standard","I250";
;
CDS_LIB"mstr_standard"
BODY_TYPE"PLUMBING"
HDL_TAP"TRUE";
"B \NAC \NWC"5;
"S \NAC"
BN"6"74;
%"TAP"
"1","(-5675,5200)","2","mstr_standard","I251";
;
CDS_LIB"mstr_standard"
BODY_TYPE"PLUMBING"
HDL_TAP"TRUE";
"B \NAC \NWC"5;
"S \NAC"
BN"7"75;
%"TAP"
"1","(-5875,5850)","2","mstr_standard","I252";
;
CDS_LIB"mstr_standard"
BODY_TYPE"PLUMBING"
HDL_TAP"TRUE";
"B \NAC \NWC"6;
"S \NAC"
BN"0"66;
%"TAP"
"1","(-5875,5650)","2","mstr_standard","I253";
;
CDS_LIB"mstr_standard"
BODY_TYPE"PLUMBING"
HDL_TAP"TRUE";
"B \NAC \NWC"6;
"S \NAC"
BN"2"68;
%"TAP"
"1","(-5875,5750)","2","mstr_standard","I254";
;
CDS_LIB"mstr_standard"
BODY_TYPE"PLUMBING"
HDL_TAP"TRUE";
"B \NAC \NWC"6;
"S \NAC"
BN"1"67;
%"TAP"
"1","(-5875,5550)","2","mstr_standard","I255";
;
CDS_LIB"mstr_standard"
BODY_TYPE"PLUMBING"
HDL_TAP"TRUE";
"B \NAC \NWC"6;
"S \NAC"
BN"3"69;
%"TAP"
"1","(-5875,5450)","2","mstr_standard","I256";
;
CDS_LIB"mstr_standard"
BODY_TYPE"PLUMBING"
HDL_TAP"TRUE";
"B \NAC \NWC"6;
"S \NAC"
BN"4"63;
%"TAP"
"1","(-5875,5250)","2","mstr_standard","I257";
;
CDS_LIB"mstr_standard"
BODY_TYPE"PLUMBING"
HDL_TAP"TRUE";
"B \NAC \NWC"6;
"S \NAC"
BN"6"70;
%"TAP"
"1","(-5875,5350)","2","mstr_standard","I258";
;
CDS_LIB"mstr_standard"
BODY_TYPE"PLUMBING"
HDL_TAP"TRUE";
"B \NAC \NWC"6;
"S \NAC"
BN"5"64;
%"TAP"
"1","(-5875,5150)","2","mstr_standard","I259";
;
CDS_LIB"mstr_standard"
BODY_TYPE"PLUMBING"
HDL_TAP"TRUE";
"B \NAC \NWC"6;
"S \NAC"
BN"7"65;
%"TAP"
"1","(-5675,5000)","2","mstr_standard","I260";
;
CDS_LIB"mstr_standard"
BODY_TYPE"PLUMBING"
HDL_TAP"TRUE";
"B \NAC \NWC"5;
"S \NAC"
BN"9"59;
%"TAP"
"1","(-5675,5100)","2","mstr_standard","I261";
;
CDS_LIB"mstr_standard"
BODY_TYPE"PLUMBING"
HDL_TAP"TRUE";
"B \NAC \NWC"5;
"S \NAC"
BN"8"58;
%"TAP"
"1","(-5675,4850)","2","mstr_standard","I262";
;
CDS_LIB"mstr_standard"
BODY_TYPE"PLUMBING"
HDL_TAP"TRUE";
"B \NAC \NWC"7;
"S \NAC"
BN"0"60;
%"TAP"
"1","(-5675,4750)","2","mstr_standard","I263";
;
CDS_LIB"mstr_standard"
BODY_TYPE"PLUMBING"
HDL_TAP"TRUE";
"B \NAC \NWC"7;
"S \NAC"
BN"1"61;
%"TAP"
"1","(-5675,4650)","2","mstr_standard","I264";
;
CDS_LIB"mstr_standard"
BODY_TYPE"PLUMBING"
HDL_TAP"TRUE";
"B \NAC \NWC"7;
"S \NAC"
BN"2"62;
%"TAP"
"1","(-5675,4550)","2","mstr_standard","I265";
;
CDS_LIB"mstr_standard"
BODY_TYPE"PLUMBING"
HDL_TAP"TRUE";
"B \NAC \NWC"7;
"S \NAC"
BN"3"54;
%"TAP"
"1","(-5675,4450)","2","mstr_standard","I266";
;
CDS_LIB"mstr_standard"
BODY_TYPE"PLUMBING"
HDL_TAP"TRUE";
"B \NAC \NWC"7;
"S \NAC"
BN"4"55;
%"TAP"
"1","(-5675,4350)","2","mstr_standard","I267";
;
CDS_LIB"mstr_standard"
BODY_TYPE"PLUMBING"
HDL_TAP"TRUE";
"B \NAC \NWC"7;
"S \NAC"
BN"5"53;
%"TAP"
"1","(-5675,4250)","2","mstr_standard","I268";
;
CDS_LIB"mstr_standard"
BODY_TYPE"PLUMBING"
HDL_TAP"TRUE";
"B \NAC \NWC"7;
"S \NAC"
BN"6"56;
%"TAP"
"1","(-5675,4150)","2","mstr_standard","I269";
;
CDS_LIB"mstr_standard"
BODY_TYPE"PLUMBING"
HDL_TAP"TRUE";
"B \NAC \NWC"7;
"S \NAC"
BN"7"57;
%"TAP"
"1","(-5875,4950)","2","mstr_standard","I270";
;
CDS_LIB"mstr_standard"
BODY_TYPE"PLUMBING"
HDL_TAP"TRUE";
"B \NAC \NWC"6;
"S \NAC"
BN"9"46;
%"TAP"
"1","(-5875,5050)","2","mstr_standard","I271";
;
CDS_LIB"mstr_standard"
BODY_TYPE"PLUMBING"
HDL_TAP"TRUE";
"B \NAC \NWC"6;
"S \NAC"
BN"8"45;
%"TAP"
"1","(-5875,4800)","2","mstr_standard","I272";
;
CDS_LIB"mstr_standard"
BODY_TYPE"PLUMBING"
HDL_TAP"TRUE";
"B \NAC \NWC"8;
"S \NAC"
BN"0"44;
%"TAP"
"1","(-5875,4700)","2","mstr_standard","I273";
;
CDS_LIB"mstr_standard"
BODY_TYPE"PLUMBING"
HDL_TAP"TRUE";
"B \NAC \NWC"8;
"S \NAC"
BN"1"47;
%"TAP"
"1","(-5875,4500)","2","mstr_standard","I274";
;
CDS_LIB"mstr_standard"
BODY_TYPE"PLUMBING"
HDL_TAP"TRUE";
"B \NAC \NWC"8;
"S \NAC"
BN"3"49;
%"TAP"
"1","(-5875,4600)","2","mstr_standard","I275";
;
CDS_LIB"mstr_standard"
BODY_TYPE"PLUMBING"
HDL_TAP"TRUE";
"B \NAC \NWC"8;
"S \NAC"
BN"2"48;
%"TAP"
"1","(-5875,4400)","2","mstr_standard","I276";
;
CDS_LIB"mstr_standard"
BODY_TYPE"PLUMBING"
HDL_TAP"TRUE";
"B \NAC \NWC"8;
"S \NAC"
BN"4"43;
%"TAP"
"1","(-5875,4300)","2","mstr_standard","I277";
;
CDS_LIB"mstr_standard"
BODY_TYPE"PLUMBING"
HDL_TAP"TRUE";
"B \NAC \NWC"8;
"S \NAC"
BN"5"50;
%"TAP"
"1","(-5875,4100)","2","mstr_standard","I278";
;
CDS_LIB"mstr_standard"
BODY_TYPE"PLUMBING"
HDL_TAP"TRUE";
"B \NAC \NWC"8;
"S \NAC"
BN"7"52;
%"TAP"
"1","(-5875,4200)","2","mstr_standard","I279";
;
CDS_LIB"mstr_standard"
BODY_TYPE"PLUMBING"
HDL_TAP"TRUE";
"B \NAC \NWC"8;
"S \NAC"
BN"6"51;
%"TAP"
"1","(-5675,4050)","2","mstr_standard","I284";
;
CDS_LIB"mstr_standard"
BODY_TYPE"PLUMBING"
HDL_TAP"TRUE";
"B \NAC \NWC"7;
"S \NAC"
BN"8"41;
%"TAP"
"1","(-5675,3950)","2","mstr_standard","I285";
;
CDS_LIB"mstr_standard"
BODY_TYPE"PLUMBING"
HDL_TAP"TRUE";
"B \NAC \NWC"7;
"S \NAC"
BN"9"42;
%"TAP"
"1","(-5875,4000)","2","mstr_standard","I286";
;
CDS_LIB"mstr_standard"
BODY_TYPE"PLUMBING"
HDL_TAP"TRUE";
"B \NAC \NWC"8;
"S \NAC"
BN"8"39;
%"TAP"
"1","(-5875,3900)","2","mstr_standard","I287";
;
CDS_LIB"mstr_standard"
BODY_TYPE"PLUMBING"
HDL_TAP"TRUE";
"B \NAC \NWC"8;
"S \NAC"
BN"9"40;
%"TAP"
"1","(-5875,3750)","2","mstr_standard","I288";
;
CDS_LIB"mstr_standard"
BODY_TYPE"PLUMBING"
HDL_TAP"TRUE";
"B \NAC \NWC"10;
"S \NAC"
BN"0"28;
%"TAP"
"1","(-5875,3700)","2","mstr_standard","I289";
;
CDS_LIB"mstr_standard"
BODY_TYPE"PLUMBING"
HDL_TAP"TRUE";
"B \NAC \NWC"10;
"S \NAC"
BN"1"29;
%"TAP"
"1","(-5875,3600)","2","mstr_standard","I290";
;
CDS_LIB"mstr_standard"
BODY_TYPE"PLUMBING"
HDL_TAP"TRUE";
"B \NAC \NWC"10;
"S \NAC"
BN"3"31;
%"TAP"
"1","(-5875,3650)","2","mstr_standard","I291";
;
CDS_LIB"mstr_standard"
BODY_TYPE"PLUMBING"
HDL_TAP"TRUE";
"B \NAC \NWC"10;
"S \NAC"
BN"2"30;
%"TAP"
"1","(-5875,3550)","2","mstr_standard","I292";
;
CDS_LIB"mstr_standard"
BODY_TYPE"PLUMBING"
HDL_TAP"TRUE";
"B \NAC \NWC"10;
"S \NAC"
BN"4"32;
%"TAP"
"1","(-5875,3500)","2","mstr_standard","I293";
;
CDS_LIB"mstr_standard"
BODY_TYPE"PLUMBING"
HDL_TAP"TRUE";
"B \NAC \NWC"10;
"S \NAC"
BN"5"26;
%"TAP"
"1","(-5875,3450)","2","mstr_standard","I294";
;
CDS_LIB"mstr_standard"
BODY_TYPE"PLUMBING"
HDL_TAP"TRUE";
"B \NAC \NWC"10;
"S \NAC"
BN"6"27;
%"TAP"
"1","(-5875,3350)","2","mstr_standard","I295";
;
CDS_LIB"mstr_standard"
BODY_TYPE"PLUMBING"
HDL_TAP"TRUE";
"B \NAC \NWC"9;
"S \NAC"
BN"0"33;
%"TAP"
"1","(-5875,3250)","2","mstr_standard","I296";
;
CDS_LIB"mstr_standard"
BODY_TYPE"PLUMBING"
HDL_TAP"TRUE";
"B \NAC \NWC"9;
"S \NAC"
BN"2"35;
%"TAP"
"1","(-5875,3300)","2","mstr_standard","I297";
;
CDS_LIB"mstr_standard"
BODY_TYPE"PLUMBING"
HDL_TAP"TRUE";
"B \NAC \NWC"9;
"S \NAC"
BN"1"34;
%"TAP"
"1","(-5875,3200)","2","mstr_standard","I298";
;
CDS_LIB"mstr_standard"
BODY_TYPE"PLUMBING"
HDL_TAP"TRUE";
"B \NAC \NWC"9;
"S \NAC"
BN"3"36;
%"TAP"
"1","(-5875,3150)","2","mstr_standard","I299";
;
CDS_LIB"mstr_standard"
BODY_TYPE"PLUMBING"
HDL_TAP"TRUE";
"B \NAC \NWC"9;
"S \NAC"
BN"4"37;
%"TAP"
"1","(-5875,3100)","2","mstr_standard","I300";
;
CDS_LIB"mstr_standard"
BODY_TYPE"PLUMBING"
HDL_TAP"TRUE";
"B \NAC \NWC"9;
"S \NAC"
BN"5"38;
%"TAP"
"1","(-5875,3050)","2","mstr_standard","I301";
;
CDS_LIB"mstr_standard"
BODY_TYPE"PLUMBING"
HDL_TAP"TRUE";
"B \NAC \NWC"9;
"S \NAC"
BN"6"25;
%"Q_RES"
"1","(-6550,2050)","0","pure_quanta","I314";
;
LOCATION"R509"
$SEC"1"
CDS_SEC"1"
PACK_TYPE"0402LF"
TOLERANCE"1%"
VALUE"15"
MATERIAL"CHIP"
WATTAGE"1/16W"
CDS_LIB"pure_quanta"
PART_NUMBER"CS01502FB03";
"B"
$PN"2"12;
"A"
$PN"1"11;
END.
